# T6G (Grand Teton) — schematic netlist excerpt (pin names and nets, part order shuffled) for the footprints in the layout excerpt that follows; sources: Cadence DE-HDL packaged netlist, KiCad conversion of 04192023_DAF0TMB3IC0_F0TG_MB_C_brd_V02_OCP.brd

C874  Q_CAP_DIFFBUS  DIFF BUS_0.22UF 6.3V 20% X6S  pkg C0201  page 64 : \1\ = P5E_CPU0_P3_TX_C_DN<13> ; \2\ = P5E_CPU0_P3_TX_DN<13>
PR6544  Q_RES  0 5% CHIP  pkg 0402LF  page 364 : A = NC_P0V9_RETIMER_CPU1_IMON8 ; B = GND
C2633  Q_CAP  22UF 4V 20% X6S  pkg C0402  page 70 : A = PVDD11_S3_P0 ; B = GND

(kicad_pcb
	(version 20260206)
	(generator "pcbnew")
	(generator_version "10.0")
	(general
		(thickness 1.6)
		(legacy_teardrops no)
	)
	(paper "A4")
	(title_block
		(title "04192023_DAF0TMB3IC0_F0TG_MB_C_brd_V02_OCP.brd")
		(comment 1 "Grand Teton / footprints 2510-2512 of 8354")
	)
	(layers
		(0 "F.Cu" signal "TOP")
		(4 "In1.Cu" signal "GND")
		(6 "In2.Cu" signal "IN1")
		(8 "In3.Cu" signal "GND1")
		(10 "In4.Cu" signal "IN2")
		(12 "In5.Cu" signal "GND2")
		(14 "In6.Cu" signal "IN3")
		(16 "In7.Cu" signal "GND3")
		(18 "In8.Cu" signal "VCC")
		(20 "In9.Cu" signal "VCC1")
		(22 "In10.Cu" signal "GND4")
		(24 "In11.Cu" signal "IN4")
		(26 "In12.Cu" signal "GND5")
		(28 "In13.Cu" signal "IN5")
		(30 "In14.Cu" signal "GND6")
		(32 "In15.Cu" signal "IN6")
		(34 "In16.Cu" signal "GND7")
		(2 "B.Cu" signal "BOTTOM")
		(9 "F.Adhes" user "F.Adhesive")
		(11 "B.Adhes" user "B.Adhesive")
		(13 "F.Paste" user "Package Geometry/Pastemask Top")
		(15 "B.Paste" user "Package Geometry/Pastemask Bottom")
		(5 "F.SilkS" user "Ref Des/Silkscreen Top")
		(7 "B.SilkS" user "Ref Des/Silkscreen Bottom")
		(1 "F.Mask" user "Board Geometry/Soldermask Top")
		(3 "B.Mask" user "Board Geometry/Soldermask Bottom")
		(17 "Dwgs.User" user "User.Drawings")
		(19 "Cmts.User" user "User.Comments")
		(21 "Eco1.User" user "User.Eco1")
		(23 "Eco2.User" user "User.Eco2")
		(25 "Edge.Cuts" user "Board Geometry/Outline")
		(27 "Margin" user)
		(31 "F.CrtYd" user "Package Geometry/Place Bound Top")
		(29 "B.CrtYd" user "Package Geometry/Place Bound Bottom")
		(35 "F.Fab" user "Ref Des/Assembly Top")
		(33 "B.Fab" user "Ref Des/Assembly Bottom")
	)
	(footprint ""
		(layer "F.Cu")
		(at 364.167166 -261.747762 -90)
		(property "Reference" "C2633"
			(at 0 0 270)
			(layer "F.SilkS")
			(hide yes)
			(effects
				(font
					(size 1.27 1.27)
				)
			)
		)
		(property "Value" ""
			(at 0 0 270)
			(layer "F.Fab")
			(effects
				(font
					(size 1.27 1.27)
				)
			)
		)
		(duplicate_pad_numbers_are_jumpers no)
		(fp_line
			(start -0.7874 0.4064)
			(end -0.7874 -0.4064)
			(stroke
				(width 0.1524)
				(type default)
			)
			(layer "F.SilkS")
		)
		(fp_line
			(start 0.7874 0.4064)
			(end -0.7874 0.4064)
			(stroke
				(width 0.1524)
				(type default)
			)
			(layer "F.SilkS")
		)
		(fp_line
			(start -0.7874 -0.4064)
			(end 0.7874 -0.4064)
			(stroke
				(width 0.1524)
				(type default)
			)
			(layer "F.SilkS")
		)
		(fp_line
			(start 0.7874 -0.4064)
			(end 0.7874 0.4064)
			(stroke
				(width 0.1524)
				(type default)
			)
			(layer "F.SilkS")
		)
		(fp_line
			(start -0.67945 0.3048)
			(end -0.67945 -0.305054)
			(stroke
				(width 0.1)
				(type default)
			)
			(layer "F.Fab")
		)
		(fp_line
			(start -0.12065 0.3048)
			(end -0.67945 0.3048)
			(stroke
				(width 0.1)
				(type default)
			)
			(layer "F.Fab")
		)
		(fp_line
			(start 0.120396 0.3048)
			(end 0.120396 0.2794)
			(stroke
				(width 0.1)
				(type default)
			)
			(layer "F.Fab")
		)
		(fp_line
			(start 0.67945 0.3048)
			(end 0.120396 0.3048)
			(stroke
				(width 0.1)
				(type default)
			)
			(layer "F.Fab")
		)
		(fp_line
			(start -0.12065 0.2794)
			(end -0.12065 0.3048)
			(stroke
				(width 0.1)
				(type default)
			)
			(layer "F.Fab")
		)
		(fp_line
			(start 0.120396 0.2794)
			(end -0.12065 0.2794)
			(stroke
				(width 0.1)
				(type default)
			)
			(layer "F.Fab")
		)
		(fp_line
			(start -0.12065 -0.2794)
			(end 0.12065 -0.2794)
			(stroke
				(width 0.1)
				(type default)
			)
			(layer "F.Fab")
		)
		(fp_line
			(start 0.12065 -0.2794)
			(end 0.12065 -0.3048)
			(stroke
				(width 0.1)
				(type default)
			)
			(layer "F.Fab")
		)
		(fp_line
			(start 0.12065 -0.3048)
			(end 0.67945 -0.3048)
			(stroke
				(width 0.1)
				(type default)
			)
			(layer "F.Fab")
		)
		(fp_line
			(start 0.67945 -0.3048)
			(end 0.67945 0.3048)
			(stroke
				(width 0.1)
				(type default)
			)
			(layer "F.Fab")
		)
		(fp_line
			(start -0.67945 -0.305054)
			(end -0.12065 -0.305054)
			(stroke
				(width 0.1)
				(type default)
			)
			(layer "F.Fab")
		)
		(fp_line
			(start -0.12065 -0.305054)
			(end -0.12065 -0.2794)
			(stroke
				(width 0.1)
				(type default)
			)
			(layer "F.Fab")
		)
		(pad "1" smd circle
			(at -0.40005 0 270)
			(size 0 0)
			(layers "F.Cu" "F.Mask" "F.Paste")
			(net "PVDD11_S3_P0")
		)
		(pad "2" smd circle
			(at 0.40005 0 270)
			(size 0 0)
			(layers "F.Cu" "F.Mask" "F.Paste")
			(net "GND")
		)
	)
	(footprint ""
		(layer "F.Cu")
		(at 392.531092 -378.95403 -90)
		(property "Reference" "C874"
			(at 0 0 270)
			(layer "F.SilkS")
			(hide yes)
			(effects
				(font
					(size 1.27 1.27)
				)
			)
		)
		(property "Value" ""
			(at 0 0 270)
			(layer "F.Fab")
			(effects
				(font
					(size 1.27 1.27)
				)
			)
		)
		(duplicate_pad_numbers_are_jumpers no)
		(fp_line
			(start -0.299974 0.150114)
			(end -0.299974 -0.150114)
			(stroke
				(width 0.1)
				(type default)
			)
			(layer "F.Fab")
		)
		(fp_line
			(start 0.299974 0.150114)
			(end -0.299974 0.150114)
			(stroke
				(width 0.1)
				(type default)
			)
			(layer "F.Fab")
		)
		(fp_line
			(start -0.299974 -0.150114)
			(end 0.299974 -0.150114)
			(stroke
				(width 0.1)
				(type default)
			)
			(layer "F.Fab")
		)
		(fp_line
			(start 0.299974 -0.150114)
			(end 0.299974 0.150114)
			(stroke
				(width 0.1)
				(type default)
			)
			(layer "F.Fab")
		)
		(pad "1" smd rect
			(at -0.2667 0 270)
			(size 0.3048 0.381)
			(layers "F.Cu" "F.Mask" "F.Paste")
			(net "P5E_CPU0_P3_TX_C_DN<13>")
		)
		(pad "2" smd rect
			(at 0.2667 0 270)
			(size 0.3048 0.381)
			(layers "F.Cu" "F.Mask" "F.Paste")
			(net "P5E_CPU0_P3_TX_DN<13>")
		)
	)
	(footprint ""
		(layer "F.Cu")
		(at 11.717782 -415.263584 90)
		(property "Reference" "PR6544"
			(at 0 0 90)
			(layer "F.SilkS")
			(hide yes)
			(effects
				(font
					(size 1.27 1.27)
				)
			)
		)
		(property "Value" ""
			(at 0 0 90)
			(layer "F.Fab")
			(effects
				(font
					(size 1.27 1.27)
				)
			)
		)
		(duplicate_pad_numbers_are_jumpers no)
		(fp_line
			(start 0.7874 -0.4064)
			(end 0.7874 0.4064)
			(stroke
				(width 0.1524)
				(type default)
			)
			(layer "F.SilkS")
		)
		(fp_line
			(start -0.7874 -0.4064)
			(end 0.7874 -0.4064)
			(stroke
				(width 0.1524)
				(type default)
			)
			(layer "F.SilkS")
		)
		(fp_line
			(start 0.7874 0.4064)
			(end -0.7874 0.4064)
			(stroke
				(width 0.1524)
				(type default)
			)
			(layer "F.SilkS")
		)
		(fp_line
			(start -0.7874 0.4064)
			(end -0.7874 -0.4064)
			(stroke
				(width 0.1524)
				(type default)
			)
			(layer "F.SilkS")
		)
		(fp_line
			(start -0.12065 -0.305054)
			(end -0.12065 -0.2794)
			(stroke
				(width 0.1)
				(type default)
			)
			(layer "F.Fab")
		)
		(fp_line
			(start -0.67945 -0.305054)
			(end -0.12065 -0.305054)
			(stroke
				(width 0.1)
				(type default)
			)
			(layer "F.Fab")
		)
		(fp_line
			(start 0.67945 -0.3048)
			(end 0.67945 0.3048)
			(stroke
				(width 0.1)
				(type default)
			)
			(layer "F.Fab")
		)
		(fp_line
			(start 0.12065 -0.3048)
			(end 0.67945 -0.3048)
			(stroke
				(width 0.1)
				(type default)
			)
			(layer "F.Fab")
		)
		(fp_line
			(start 0.12065 -0.2794)
			(end 0.12065 -0.3048)
			(stroke
				(width 0.1)
				(type default)
			)
			(layer "F.Fab")
		)
		(fp_line
			(start -0.12065 -0.2794)
			(end 0.12065 -0.2794)
			(stroke
				(width 0.1)
				(type default)
			)
			(layer "F.Fab")
		)
		(fp_line
			(start 0.120396 0.2794)
			(end -0.12065 0.2794)
			(stroke
				(width 0.1)
				(type default)
			)
			(layer "F.Fab")
		)
		(fp_line
			(start -0.12065 0.2794)
			(end -0.12065 0.3048)
			(stroke
				(width 0.1)
				(type default)
			)
			(layer "F.Fab")
		)
		(fp_line
			(start 0.67945 0.3048)
			(end 0.120396 0.3048)
			(stroke
				(width 0.1)
				(type default)
			)
			(layer "F.Fab")
		)
		(fp_line
			(start 0.120396 0.3048)
			(end 0.120396 0.2794)
			(stroke
				(width 0.1)
				(type default)
			)
			(layer "F.Fab")
		)
		(fp_line
			(start -0.12065 0.3048)
			(end -0.67945 0.3048)
			(stroke
				(width 0.1)
				(type default)
			)
			(layer "F.Fab")
		)
		(fp_line
			(start -0.67945 0.3048)
			(end -0.67945 -0.305054)
			(stroke
				(width 0.1)
				(type default)
			)
			(layer "F.Fab")
		)
		(pad "1" smd circle
			(at -0.40005 0 90)
			(size 0 0)
			(layers "F.Cu" "F.Mask" "F.Paste")
			(net "NC_P0V9_RETIMER_CPU1_IMON8")
		)
		(pad "2" smd circle
			(at 0.40005 0 90)
			(size 0 0)
			(layers "F.Cu" "F.Mask" "F.Paste")
			(net "GND")
		)
	)
)
